(kicad_pcb
	(version 20241229)
	(generator "pcbnew")
	(generator_version "9.0")
	(general
		(thickness 1.62)
		(legacy_teardrops no)
	)
	(paper "A3")
	(title_block
		(title "COM Express 7 Baseboard")
		(date "2025-02-04")
		(rev "1.1.2")
		(company "Antmicro Ltd")
		(comment 1 "www.antmicro.com")
		(comment 9 "footprint 489 of 802 (J12), pads 286-325 of 450")
	)
	(layers
		(0 "F.Cu" signal)
		(4 "In1.Cu" signal)
		(6 "In2.Cu" signal)
		(8 "In3.Cu" signal)
		(10 "In4.Cu" signal)
		(12 "In5.Cu" signal)
		(14 "In6.Cu" signal)
		(2 "B.Cu" signal)
		(9 "F.Adhes" user "F.Adhesive")
		(11 "B.Adhes" user "B.Adhesive")
		(13 "F.Paste" user)
		(15 "B.Paste" user)
		(5 "F.SilkS" user "F.Silkscreen")
		(7 "B.SilkS" user "B.Silkscreen")
		(1 "F.Mask" user)
		(3 "B.Mask" user)
		(17 "Dwgs.User" user "User.Drawings")
		(19 "Cmts.User" user "User.Comments")
		(21 "Eco1.User" user "User.Eco1")
		(23 "Eco2.User" user "User.Eco2")
		(25 "Edge.Cuts" user)
		(27 "Margin" user)
		(31 "F.CrtYd" user "F.Courtyard")
		(29 "B.CrtYd" user "B.Courtyard")
		(35 "F.Fab" user)
		(33 "B.Fab" user)
	)
	(footprint "antmicro-footprints:EPT_401-51501-51"
		(layer "F.Cu")
		(at 203.275 159.81)
		(property "Reference" "J12"
			(at 30.975 -10.45 0)
			(layer "F.SilkS")
			(effects
				(font
					(size 0.7 0.7)
					(thickness 0.15)
				)
				(justify right top)
			)
		)
		(property "Value" "Plug_Bus_CE7_EPT_401-51501-51"
			(at -3.225 52.665 0)
			(layer "F.Fab")
			(hide yes)
			(effects
				(font
					(size 0.7 0.7)
					(thickness 0.15)
				)
				(justify left top)
			)
		)
		(property "Datasheet" "https://www.farnell.com/datasheets/1905093.pdf"
			(at 0 0 0)
			(layer "F.Fab")
			(hide yes)
			(effects
				(font
					(size 1.27 1.27)
					(thickness 0.15)
				)
			)
		)
		(property "Author" "Antmicro"
			(at 406.55 319.62 0)
			(layer "F.Fab")
			(hide yes)
			(effects
				(font
					(size 1 1)
					(thickness 0.15)
				)
			)
		)
		(property "License" "Apache-2.0"
			(at 406.55 319.62 0)
			(layer "F.Fab")
			(hide yes)
			(effects
				(font
					(size 1 1)
					(thickness 0.15)
				)
			)
		)
		(property "MPN" "401-51501-51"
			(at 406.55 319.62 0)
			(layer "F.Fab")
			(hide yes)
			(effects
				(font
					(size 1 1)
					(thickness 0.15)
				)
			)
		)
		(property "Manufacturer" "ept"
			(at 406.55 319.62 0)
			(layer "F.Fab")
			(hide yes)
			(effects
				(font
					(size 1 1)
					(thickness 0.15)
				)
			)
		)
		(sheetname "Com Express 7 Interfaces")
		(sheetfile "com_express_7_interfaces.kicad_sch")
		(attr smd)
		(pad "C61" smd rect
			(at 2.75 -3.125)
			(size 0.3 1.75)
			(layers "F.Cu" "F.Mask" "F.Paste")
			(net 883 "unconnected-(J12N-PCIE_RX19+-PadC61)")
			(pinfunction "PCIE_RX19+")
			(pintype "input+no_connect")
			(teardrops
				(best_length_ratio 0.2)
				(max_length 1)
				(best_width_ratio 0.9)
				(max_width 2)
				(curved_edges yes)
				(filter_ratio 0.9)
				(enabled yes)
				(allow_two_segments yes)
				(prefer_zone_connections yes)
			)
		)
		(pad "C62" smd rect
			(at 3.25 -3.125)
			(size 0.3 1.75)
			(layers "F.Cu" "F.Mask" "F.Paste")
			(net 884 "unconnected-(J12N-PCIE_RX19--PadC62)")
			(pinfunction "PCIE_RX19-")
			(pintype "input+no_connect")
			(teardrops
				(best_length_ratio 0.2)
				(max_length 1)
				(best_width_ratio 0.9)
				(max_width 2)
				(curved_edges yes)
				(filter_ratio 0.9)
				(enabled yes)
				(allow_two_segments yes)
				(prefer_zone_connections yes)
			)
		)
		(pad "C63" smd rect
			(at 3.75 -3.125)
			(size 0.3 1.75)
			(layers "F.Cu" "F.Mask" "F.Paste")
			(net 435 "unconnected-(J12M-RSVD-PadC63)")
			(pinfunction "RSVD")
			(pintype "no_connect")
			(teardrops
				(best_length_ratio 0.2)
				(max_length 1)
				(best_width_ratio 0.9)
				(max_width 2)
				(curved_edges yes)
				(filter_ratio 0.9)
				(enabled yes)
				(allow_two_segments yes)
				(prefer_zone_connections yes)
			)
		)
		(pad "C64" smd rect
			(at 4.25 -3.125)
			(size 0.3 1.75)
			(layers "F.Cu" "F.Mask" "F.Paste")
			(net 436 "unconnected-(J12M-RSVD-PadC64)")
			(pinfunction "RSVD")
			(pintype "no_connect")
			(teardrops
				(best_length_ratio 0.2)
				(max_length 1)
				(best_width_ratio 0.9)
				(max_width 2)
				(curved_edges yes)
				(filter_ratio 0.9)
				(enabled yes)
				(allow_two_segments yes)
				(prefer_zone_connections yes)
			)
		)
		(pad "C65" smd rect
			(at 4.75 -3.125)
			(size 0.3 1.75)
			(layers "F.Cu" "F.Mask" "F.Paste")
			(net 437 "unconnected-(J12N-PCIE_RX20+-PadC65)")
			(pinfunction "PCIE_RX20+")
			(pintype "input+no_connect")
			(teardrops
				(best_length_ratio 0.2)
				(max_length 1)
				(best_width_ratio 0.9)
				(max_width 2)
				(curved_edges yes)
				(filter_ratio 0.9)
				(enabled yes)
				(allow_two_segments yes)
				(prefer_zone_connections yes)
			)
		)
		(pad "C66" smd rect
			(at 5.25 -3.125)
			(size 0.3 1.75)
			(layers "F.Cu" "F.Mask" "F.Paste")
			(net 438 "unconnected-(J12N-PCIE_RX20--PadC66)")
			(pinfunction "PCIE_RX20-")
			(pintype "input+no_connect")
			(teardrops
				(best_length_ratio 0.2)
				(max_length 1)
				(best_width_ratio 0.9)
				(max_width 2)
				(curved_edges yes)
				(filter_ratio 0.9)
				(enabled yes)
				(allow_two_segments yes)
				(prefer_zone_connections yes)
			)
		)
		(pad "C67" smd rect
			(at 5.75 -3.125)
			(size 0.3 1.75)
			(layers "F.Cu" "F.Mask" "F.Paste")
			(net 439 "Net-(J12L-RAPID_SHUTDOWN)")
			(pinfunction "RAPID_SHUTDOWN")
			(pintype "input")
			(teardrops
				(best_length_ratio 0.2)
				(max_length 1)
				(best_width_ratio 0.9)
				(max_width 2)
				(curved_edges yes)
				(filter_ratio 0.9)
				(enabled yes)
				(allow_two_segments yes)
				(prefer_zone_connections yes)
			)
		)
		(pad "C68" smd rect
			(at 6.25 -3.125)
			(size 0.3 1.75)
			(layers "F.Cu" "F.Mask" "F.Paste")
			(net 440 "unconnected-(J12N-PCIE_RX21+-PadC68)")
			(pinfunction "PCIE_RX21+")
			(pintype "input+no_connect")
			(teardrops
				(best_length_ratio 0.2)
				(max_length 1)
				(best_width_ratio 0.9)
				(max_width 2)
				(curved_edges yes)
				(filter_ratio 0.9)
				(enabled yes)
				(allow_two_segments yes)
				(prefer_zone_connections yes)
			)
		)
		(pad "C69" smd rect
			(at 6.75 -3.125)
			(size 0.3 1.75)
			(layers "F.Cu" "F.Mask" "F.Paste")
			(net 441 "unconnected-(J12N-PCIE_RX21--PadC69)")
			(pinfunction "PCIE_RX21-")
			(pintype "input+no_connect")
			(teardrops
				(best_length_ratio 0.2)
				(max_length 1)
				(best_width_ratio 0.9)
				(max_width 2)
				(curved_edges yes)
				(filter_ratio 0.9)
				(enabled yes)
				(allow_two_segments yes)
				(prefer_zone_connections yes)
			)
		)
		(pad "C70" smd rect
			(at 7.25 -3.125)
			(size 0.3 1.75)
			(layers "F.Cu" "F.Mask" "F.Paste")
			(net 1 "GND")
			(pinfunction "GND(FIXED)")
			(pintype "passive")
			(teardrops
				(best_length_ratio 0.2)
				(max_length 1)
				(best_width_ratio 0.9)
				(max_width 2)
				(curved_edges yes)
				(filter_ratio 0.9)
				(enabled yes)
				(allow_two_segments yes)
				(prefer_zone_connections yes)
			)
		)
		(pad "C71" smd rect
			(at 7.75 -3.125)
			(size 0.3 1.75)
			(layers "F.Cu" "F.Mask" "F.Paste")
			(net 442 "unconnected-(J12N-PCIE_RX22+-PadC71)")
			(pinfunction "PCIE_RX22+")
			(pintype "input+no_connect")
			(teardrops
				(best_length_ratio 0.2)
				(max_length 1)
				(best_width_ratio 0.9)
				(max_width 2)
				(curved_edges yes)
				(filter_ratio 0.9)
				(enabled yes)
				(allow_two_segments yes)
				(prefer_zone_connections yes)
			)
		)
		(pad "C72" smd rect
			(at 8.25 -3.125)
			(size 0.3 1.75)
			(layers "F.Cu" "F.Mask" "F.Paste")
			(net 443 "unconnected-(J12N-PCIE_RX22--PadC72)")
			(pinfunction "PCIE_RX22-")
			(pintype "input+no_connect")
			(teardrops
				(best_length_ratio 0.2)
				(max_length 1)
				(best_width_ratio 0.9)
				(max_width 2)
				(curved_edges yes)
				(filter_ratio 0.9)
				(enabled yes)
				(allow_two_segments yes)
				(prefer_zone_connections yes)
			)
		)
		(pad "C73" smd rect
			(at 8.75 -3.125)
			(size 0.3 1.75)
			(layers "F.Cu" "F.Mask" "F.Paste")
			(net 1 "GND")
			(pinfunction "GND")
			(pintype "passive")
			(teardrops
				(best_length_ratio 0.2)
				(max_length 1)
				(best_width_ratio 0.9)
				(max_width 2)
				(curved_edges yes)
				(filter_ratio 0.9)
				(enabled yes)
				(allow_two_segments yes)
				(prefer_zone_connections yes)
			)
		)
		(pad "C74" smd rect
			(at 9.25 -3.125)
			(size 0.3 1.75)
			(layers "F.Cu" "F.Mask" "F.Paste")
			(net 444 "unconnected-(J12N-PCIE_RX23+-PadC74)")
			(pinfunction "PCIE_RX23+")
			(pintype "input+no_connect")
			(teardrops
				(best_length_ratio 0.2)
				(max_length 1)
				(best_width_ratio 0.9)
				(max_width 2)
				(curved_edges yes)
				(filter_ratio 0.9)
				(enabled yes)
				(allow_two_segments yes)
				(prefer_zone_connections yes)
			)
		)
		(pad "C75" smd rect
			(at 9.75 -3.125)
			(size 0.3 1.75)
			(layers "F.Cu" "F.Mask" "F.Paste")
			(net 445 "unconnected-(J12N-PCIE_RX23--PadC75)")
			(pinfunction "PCIE_RX23-")
			(pintype "input+no_connect")
			(teardrops
				(best_length_ratio 0.2)
				(max_length 1)
				(best_width_ratio 0.9)
				(max_width 2)
				(curved_edges yes)
				(filter_ratio 0.9)
				(enabled yes)
				(allow_two_segments yes)
				(prefer_zone_connections yes)
			)
		)
		(pad "C76" smd rect
			(at 10.25 -3.125)
			(size 0.3 1.75)
			(layers "F.Cu" "F.Mask" "F.Paste")
			(net 1 "GND")
			(pinfunction "GND")
			(pintype "passive")
			(teardrops
				(best_length_ratio 0.2)
				(max_length 1)
				(best_width_ratio 0.9)
				(max_width 2)
				(curved_edges yes)
				(filter_ratio 0.9)
				(enabled yes)
				(allow_two_segments yes)
				(prefer_zone_connections yes)
			)
		)
		(pad "C77" smd rect
			(at 10.75 -3.125)
			(size 0.3 1.75)
			(layers "F.Cu" "F.Mask" "F.Paste")
			(net 446 "unconnected-(J12M-RSVD-PadC77)")
			(pinfunction "RSVD")
			(pintype "no_connect")
			(teardrops
				(best_length_ratio 0.2)
				(max_length 1)
				(best_width_ratio 0.9)
				(max_width 2)
				(curved_edges yes)
				(filter_ratio 0.9)
				(enabled yes)
				(allow_two_segments yes)
				(prefer_zone_connections yes)
			)
		)
		(pad "C78" smd rect
			(at 11.25 -3.125)
			(size 0.3 1.75)
			(layers "F.Cu" "F.Mask" "F.Paste")
			(net 447 "unconnected-(J12N-PCIE_RX24+-PadC78)")
			(pinfunction "PCIE_RX24+")
			(pintype "input+no_connect")
			(teardrops
				(best_length_ratio 0.2)
				(max_length 1)
				(best_width_ratio 0.9)
				(max_width 2)
				(curved_edges yes)
				(filter_ratio 0.9)
				(enabled yes)
				(allow_two_segments yes)
				(prefer_zone_connections yes)
			)
		)
		(pad "C79" smd rect
			(at 11.75 -3.125)
			(size 0.3 1.75)
			(layers "F.Cu" "F.Mask" "F.Paste")
			(net 448 "unconnected-(J12N-PCIE_RX24--PadC79)")
			(pinfunction "PCIE_RX24-")
			(pintype "input+no_connect")
			(teardrops
				(best_length_ratio 0.2)
				(max_length 1)
				(best_width_ratio 0.9)
				(max_width 2)
				(curved_edges yes)
				(filter_ratio 0.9)
				(enabled yes)
				(allow_two_segments yes)
				(prefer_zone_connections yes)
			)
		)
		(pad "C80" smd rect
			(at 12.25 -3.125)
			(size 0.3 1.75)
			(layers "F.Cu" "F.Mask" "F.Paste")
			(net 1 "GND")
			(pinfunction "GND(FIXED)")
			(pintype "passive")
			(teardrops
				(best_length_ratio 0.2)
				(max_length 1)
				(best_width_ratio 0.9)
				(max_width 2)
				(curved_edges yes)
				(filter_ratio 0.9)
				(enabled yes)
				(allow_two_segments yes)
				(prefer_zone_connections yes)
			)
		)
		(pad "C81" smd rect
			(at 12.75 -3.125)
			(size 0.3 1.75)
			(layers "F.Cu" "F.Mask" "F.Paste")
			(net 449 "unconnected-(J12N-PCIE_RX25+-PadC81)")
			(pinfunction "PCIE_RX25+")
			(pintype "input+no_connect")
			(teardrops
				(best_length_ratio 0.2)
				(max_length 1)
				(best_width_ratio 0.9)
				(max_width 2)
				(curved_edges yes)
				(filter_ratio 0.9)
				(enabled yes)
				(allow_two_segments yes)
				(prefer_zone_connections yes)
			)
		)
		(pad "C82" smd rect
			(at 13.25 -3.125)
			(size 0.3 1.75)
			(layers "F.Cu" "F.Mask" "F.Paste")
			(net 450 "unconnected-(J12N-PCIE_RX25--PadC82)")
			(pinfunction "PCIE_RX25-")
			(pintype "input+no_connect")
			(teardrops
				(best_length_ratio 0.2)
				(max_length 1)
				(best_width_ratio 0.9)
				(max_width 2)
				(curved_edges yes)
				(filter_ratio 0.9)
				(enabled yes)
				(allow_two_segments yes)
				(prefer_zone_connections yes)
			)
		)
		(pad "C83" smd rect
			(at 13.75 -3.125)
			(size 0.3 1.75)
			(layers "F.Cu" "F.Mask" "F.Paste")
			(net 451 "unconnected-(J12M-RSVD-PadC83)")
			(pinfunction "RSVD")
			(pintype "no_connect")
			(teardrops
				(best_length_ratio 0.2)
				(max_length 1)
				(best_width_ratio 0.9)
				(max_width 2)
				(curved_edges yes)
				(filter_ratio 0.9)
				(enabled yes)
				(allow_two_segments yes)
				(prefer_zone_connections yes)
			)
		)
		(pad "C84" smd rect
			(at 14.25 -3.125)
			(size 0.3 1.75)
			(layers "F.Cu" "F.Mask" "F.Paste")
			(net 1 "GND")
			(pinfunction "GND")
			(pintype "passive")
			(teardrops
				(best_length_ratio 0.2)
				(max_length 1)
				(best_width_ratio 0.9)
				(max_width 2)
				(curved_edges yes)
				(filter_ratio 0.9)
				(enabled yes)
				(allow_two_segments yes)
				(prefer_zone_connections yes)
			)
		)
		(pad "C85" smd rect
			(at 14.75 -3.125)
			(size 0.3 1.75)
			(layers "F.Cu" "F.Mask" "F.Paste")
			(net 452 "unconnected-(J12N-PCIE_RX26+-PadC85)")
			(pinfunction "PCIE_RX26+")
			(pintype "input+no_connect")
			(teardrops
				(best_length_ratio 0.2)
				(max_length 1)
				(best_width_ratio 0.9)
				(max_width 2)
				(curved_edges yes)
				(filter_ratio 0.9)
				(enabled yes)
				(allow_two_segments yes)
				(prefer_zone_connections yes)
			)
		)
		(pad "C86" smd rect
			(at 15.25 -3.125)
			(size 0.3 1.75)
			(layers "F.Cu" "F.Mask" "F.Paste")
			(net 453 "unconnected-(J12N-PCIE_RX26--PadC86)")
			(pinfunction "PCIE_RX26-")
			(pintype "input+no_connect")
			(teardrops
				(best_length_ratio 0.2)
				(max_length 1)
				(best_width_ratio 0.9)
				(max_width 2)
				(curved_edges yes)
				(filter_ratio 0.9)
				(enabled yes)
				(allow_two_segments yes)
				(prefer_zone_connections yes)
			)
		)
		(pad "C87" smd rect
			(at 15.75 -3.125)
			(size 0.3 1.75)
			(layers "F.Cu" "F.Mask" "F.Paste")
			(net 1 "GND")
			(pinfunction "GND")
			(pintype "passive")
			(teardrops
				(best_length_ratio 0.2)
				(max_length 1)
				(best_width_ratio 0.9)
				(max_width 2)
				(curved_edges yes)
				(filter_ratio 0.9)
				(enabled yes)
				(allow_two_segments yes)
				(prefer_zone_connections yes)
			)
		)
		(pad "C88" smd rect
			(at 16.25 -3.125)
			(size 0.3 1.75)
			(layers "F.Cu" "F.Mask" "F.Paste")
			(net 454 "unconnected-(J12N-PCIE_RX27+-PadC88)")
			(pinfunction "PCIE_RX27+")
			(pintype "input+no_connect")
			(teardrops
				(best_length_ratio 0.2)
				(max_length 1)
				(best_width_ratio 0.9)
				(max_width 2)
				(curved_edges yes)
				(filter_ratio 0.9)
				(enabled yes)
				(allow_two_segments yes)
				(prefer_zone_connections yes)
			)
		)
		(pad "C89" smd rect
			(at 16.75 -3.125)
			(size 0.3 1.75)
			(layers "F.Cu" "F.Mask" "F.Paste")
			(net 455 "unconnected-(J12N-PCIE_RX27--PadC89)")
			(pinfunction "PCIE_RX27-")
			(pintype "input+no_connect")
			(teardrops
				(best_length_ratio 0.2)
				(max_length 1)
				(best_width_ratio 0.9)
				(max_width 2)
				(curved_edges yes)
				(filter_ratio 0.9)
				(enabled yes)
				(allow_two_segments yes)
				(prefer_zone_connections yes)
			)
		)
		(pad "C90" smd rect
			(at 17.25 -3.125)
			(size 0.3 1.75)
			(layers "F.Cu" "F.Mask" "F.Paste")
			(net 1 "GND")
			(pinfunction "GND(FIXED)")
			(pintype "passive")
			(teardrops
				(best_length_ratio 0.2)
				(max_length 1)
				(best_width_ratio 0.9)
				(max_width 2)
				(curved_edges yes)
				(filter_ratio 0.9)
				(enabled yes)
				(allow_two_segments yes)
				(prefer_zone_connections yes)
			)
		)
		(pad "C91" smd rect
			(at 17.75 -3.125)
			(size 0.3 1.75)
			(layers "F.Cu" "F.Mask" "F.Paste")
			(net 456 "unconnected-(J12N-PCIE_RX28+-PadC91)")
			(pinfunction "PCIE_RX28+")
			(pintype "input+no_connect")
			(teardrops
				(best_length_ratio 0.2)
				(max_length 1)
				(best_width_ratio 0.9)
				(max_width 2)
				(curved_edges yes)
				(filter_ratio 0.9)
				(enabled yes)
				(allow_two_segments yes)
				(prefer_zone_connections yes)
			)
		)
		(pad "C92" smd rect
			(at 18.25 -3.125)
			(size 0.3 1.75)
			(layers "F.Cu" "F.Mask" "F.Paste")
			(net 457 "unconnected-(J12N-PCIE_RX28--PadC92)")
			(pinfunction "PCIE_RX28-")
			(pintype "input+no_connect")
			(teardrops
				(best_length_ratio 0.2)
				(max_length 1)
				(best_width_ratio 0.9)
				(max_width 2)
				(curved_edges yes)
				(filter_ratio 0.9)
				(enabled yes)
				(allow_two_segments yes)
				(prefer_zone_connections yes)
			)
		)
		(pad "C93" smd rect
			(at 18.75 -3.125)
			(size 0.3 1.75)
			(layers "F.Cu" "F.Mask" "F.Paste")
			(net 1 "GND")
			(pinfunction "GND")
			(pintype "passive")
			(teardrops
				(best_length_ratio 0.2)
				(max_length 1)
				(best_width_ratio 0.9)
				(max_width 2)
				(curved_edges yes)
				(filter_ratio 0.9)
				(enabled yes)
				(allow_two_segments yes)
				(prefer_zone_connections yes)
			)
		)
		(pad "C94" smd rect
			(at 19.25 -3.125)
			(size 0.3 1.75)
			(layers "F.Cu" "F.Mask" "F.Paste")
			(net 458 "unconnected-(J12N-PCIE_RX29+-PadC94)")
			(pinfunction "PCIE_RX29+")
			(pintype "input+no_connect")
			(teardrops
				(best_length_ratio 0.2)
				(max_length 1)
				(best_width_ratio 0.9)
				(max_width 2)
				(curved_edges yes)
				(filter_ratio 0.9)
				(enabled yes)
				(allow_two_segments yes)
				(prefer_zone_connections yes)
			)
		)
		(pad "C95" smd rect
			(at 19.75 -3.125)
			(size 0.3 1.75)
			(layers "F.Cu" "F.Mask" "F.Paste")
			(net 459 "unconnected-(J12N-PCIE_RX29--PadC95)")
			(pinfunction "PCIE_RX29-")
			(pintype "input+no_connect")
			(teardrops
				(best_length_ratio 0.2)
				(max_length 1)
				(best_width_ratio 0.9)
				(max_width 2)
				(curved_edges yes)
				(filter_ratio 0.9)
				(enabled yes)
				(allow_two_segments yes)
				(prefer_zone_connections yes)
			)
		)
		(pad "C96" smd rect
			(at 20.25 -3.125)
			(size 0.3 1.75)
			(layers "F.Cu" "F.Mask" "F.Paste")
			(net 1 "GND")
			(pinfunction "GND")
			(pintype "passive")
			(teardrops
				(best_length_ratio 0.2)
				(max_length 1)
				(best_width_ratio 0.9)
				(max_width 2)
				(curved_edges yes)
				(filter_ratio 0.9)
				(enabled yes)
				(allow_two_segments yes)
				(prefer_zone_connections yes)
			)
		)
		(pad "C97" smd rect
			(at 20.75 -3.125)
			(size 0.3 1.75)
			(layers "F.Cu" "F.Mask" "F.Paste")
			(net 460 "unconnected-(J12M-RSVD-PadC97)")
			(pinfunction "RSVD")
			(pintype "no_connect")
			(teardrops
				(best_length_ratio 0.2)
				(max_length 1)
				(best_width_ratio 0.9)
				(max_width 2)
				(curved_edges yes)
				(filter_ratio 0.9)
				(enabled yes)
				(allow_two_segments yes)
				(prefer_zone_connections yes)
			)
		)
		(pad "C98" smd rect
			(at 21.25 -3.125)
			(size 0.3 1.75)
			(layers "F.Cu" "F.Mask" "F.Paste")
			(net 461 "unconnected-(J12N-PCIE_RX30+-PadC98)")
			(pinfunction "PCIE_RX30+")
			(pintype "input+no_connect")
			(teardrops
				(best_length_ratio 0.2)
				(max_length 1)
				(best_width_ratio 0.9)
				(max_width 2)
				(curved_edges yes)
				(filter_ratio 0.9)
				(enabled yes)
				(allow_two_segments yes)
				(prefer_zone_connections yes)
			)
		)
		(pad "C99" smd rect
			(at 21.75 -3.125)
			(size 0.3 1.75)
			(layers "F.Cu" "F.Mask" "F.Paste")
			(net 462 "unconnected-(J12N-PCIE_RX30--PadC99)")
			(pinfunction "PCIE_RX30-")
			(pintype "input+no_connect")
			(teardrops
				(best_length_ratio 0.2)
				(max_length 1)
				(best_width_ratio 0.9)
				(max_width 2)
				(curved_edges yes)
				(filter_ratio 0.9)
				(enabled yes)
				(allow_two_segments yes)
				(prefer_zone_connections yes)
			)
		)
		(pad "C100" smd rect
			(at 22.25 -3.125)
			(size 0.3 1.75)
			(layers "F.Cu" "F.Mask" "F.Paste")
			(net 1 "GND")
			(pinfunction "GND(FIXED)")
			(pintype "passive")
			(teardrops
				(best_length_ratio 0.2)
				(max_length 1)
				(best_width_ratio 0.9)
				(max_width 2)
				(curved_edges yes)
				(filter_ratio 0.9)
				(enabled yes)
				(allow_two_segments yes)
				(prefer_zone_connections yes)
			)
		)
	)
)
